(kicad_pcb
	(version 20260206)
	(generator "pcbnew")
	(generator_version "10.0")
	(general
		(thickness 1.6)
		(legacy_teardrops no)
	)
	(paper "A4")
	(title_block
		(title "03242023_DA0F0TMBIJ0_F0T_Motherboard_J_brd_V01_OCP.brd")
		(comment 1 "Grand Teton / footprints 105-111 of 6105")
	)
	(layers
		(0 "F.Cu" signal "TOP")
		(4 "In1.Cu" signal "GND")
		(6 "In2.Cu" signal "IN1")
		(8 "In3.Cu" signal "GND1")
		(10 "In4.Cu" signal "IN2")
		(12 "In5.Cu" signal "GND2")
		(14 "In6.Cu" signal "IN3")
		(16 "In7.Cu" signal "GND3")
		(18 "In8.Cu" signal "VCC")
		(20 "In9.Cu" signal "VCC1")
		(22 "In10.Cu" signal "GND4")
		(24 "In11.Cu" signal "IN4")
		(26 "In12.Cu" signal "GND5")
		(28 "In13.Cu" signal "IN5")
		(30 "In14.Cu" signal "GND6")
		(32 "In15.Cu" signal "IN6")
		(34 "In16.Cu" signal "GND7")
		(2 "B.Cu" signal "BOTTOM")
		(9 "F.Adhes" user "F.Adhesive")
		(11 "B.Adhes" user "B.Adhesive")
		(13 "F.Paste" user "Package Geometry/Pastemask Top")
		(15 "B.Paste" user "Package Geometry/Pastemask Bottom")
		(5 "F.SilkS" user "Ref Des/Silkscreen Top")
		(7 "B.SilkS" user "Ref Des/Silkscreen Bottom")
		(1 "F.Mask" user "Board Geometry/Soldermask Top")
		(3 "B.Mask" user "Board Geometry/Soldermask Bottom")
		(17 "Dwgs.User" user "User.Drawings")
		(19 "Cmts.User" user "User.Comments")
		(21 "Eco1.User" user "User.Eco1")
		(23 "Eco2.User" user "User.Eco2")
		(25 "Edge.Cuts" user "Board Geometry/Outline")
		(27 "Margin" user)
		(31 "F.CrtYd" user "Package Geometry/Place Bound Top")
		(29 "B.CrtYd" user "Package Geometry/Place Bound Bottom")
		(35 "F.Fab" user "Ref Des/Assembly Top")
		(33 "B.Fab" user "Ref Des/Assembly Bottom")
	)
	(footprint ""
		(layer "F.Cu")
		(at 116.561616 -245.634256 -90)
		(property "Reference" "C294"
			(at 0 0 270)
			(layer "F.SilkS")
			(hide yes)
			(effects
				(font
					(size 1.27 1.27)
				)
			)
		)
		(property "Value" ""
			(at 0 0 270)
			(layer "F.Fab")
			(effects
				(font
					(size 1.27 1.27)
				)
			)
		)
		(duplicate_pad_numbers_are_jumpers no)
		(fp_line
			(start -0.7874 0.4064)
			(end -0.7874 -0.4064)
			(stroke
				(width 0.1524)
				(type default)
			)
			(layer "F.SilkS")
		)
		(fp_line
			(start 0.7874 0.4064)
			(end -0.7874 0.4064)
			(stroke
				(width 0.1524)
				(type default)
			)
			(layer "F.SilkS")
		)
		(fp_line
			(start -0.7874 -0.4064)
			(end 0.7874 -0.4064)
			(stroke
				(width 0.1524)
				(type default)
			)
			(layer "F.SilkS")
		)
		(fp_line
			(start 0.7874 -0.4064)
			(end 0.7874 0.4064)
			(stroke
				(width 0.1524)
				(type default)
			)
			(layer "F.SilkS")
		)
		(fp_line
			(start -0.67945 0.3048)
			(end -0.67945 -0.305054)
			(stroke
				(width 0.1)
				(type default)
			)
			(layer "F.Fab")
		)
		(fp_line
			(start -0.12065 0.3048)
			(end -0.67945 0.3048)
			(stroke
				(width 0.1)
				(type default)
			)
			(layer "F.Fab")
		)
		(fp_line
			(start 0.120396 0.3048)
			(end 0.120396 0.2794)
			(stroke
				(width 0.1)
				(type default)
			)
			(layer "F.Fab")
		)
		(fp_line
			(start 0.67945 0.3048)
			(end 0.120396 0.3048)
			(stroke
				(width 0.1)
				(type default)
			)
			(layer "F.Fab")
		)
		(fp_line
			(start -0.12065 0.2794)
			(end -0.12065 0.3048)
			(stroke
				(width 0.1)
				(type default)
			)
			(layer "F.Fab")
		)
		(fp_line
			(start 0.120396 0.2794)
			(end -0.12065 0.2794)
			(stroke
				(width 0.1)
				(type default)
			)
			(layer "F.Fab")
		)
		(fp_line
			(start -0.12065 -0.2794)
			(end 0.12065 -0.2794)
			(stroke
				(width 0.1)
				(type default)
			)
			(layer "F.Fab")
		)
		(fp_line
			(start 0.12065 -0.2794)
			(end 0.12065 -0.3048)
			(stroke
				(width 0.1)
				(type default)
			)
			(layer "F.Fab")
		)
		(fp_line
			(start 0.12065 -0.3048)
			(end 0.67945 -0.3048)
			(stroke
				(width 0.1)
				(type default)
			)
			(layer "F.Fab")
		)
		(fp_line
			(start 0.67945 -0.3048)
			(end 0.67945 0.3048)
			(stroke
				(width 0.1)
				(type default)
			)
			(layer "F.Fab")
		)
		(fp_line
			(start -0.67945 -0.305054)
			(end -0.12065 -0.305054)
			(stroke
				(width 0.1)
				(type default)
			)
			(layer "F.Fab")
		)
		(fp_line
			(start -0.12065 -0.305054)
			(end -0.12065 -0.2794)
			(stroke
				(width 0.1)
				(type default)
			)
			(layer "F.Fab")
		)
		(pad "1" smd circle
			(at -0.40005 0 270)
			(size 0 0)
			(layers "F.Cu" "F.Mask" "F.Paste")
			(net "PVCCIN_CPU1")
		)
		(pad "2" smd circle
			(at 0.40005 0 270)
			(size 0 0)
			(layers "F.Cu" "F.Mask" "F.Paste")
			(net "GND")
		)
	)
	(footprint ""
		(layer "F.Cu")
		(at 153.370788 -81.88198 90)
		(property "Reference" "R3124"
			(at 0 0 90)
			(layer "F.SilkS")
			(hide yes)
			(effects
				(font
					(size 1.27 1.27)
				)
			)
		)
		(property "Value" ""
			(at 0 0 90)
			(layer "F.Fab")
			(effects
				(font
					(size 1.27 1.27)
				)
			)
		)
		(duplicate_pad_numbers_are_jumpers no)
		(fp_line
			(start 0.7874 -0.4064)
			(end 0.7874 0.4064)
			(stroke
				(width 0.1524)
				(type default)
			)
			(layer "F.SilkS")
		)
		(fp_line
			(start -0.7874 -0.4064)
			(end 0.7874 -0.4064)
			(stroke
				(width 0.1524)
				(type default)
			)
			(layer "F.SilkS")
		)
		(fp_line
			(start 0.7874 0.4064)
			(end -0.7874 0.4064)
			(stroke
				(width 0.1524)
				(type default)
			)
			(layer "F.SilkS")
		)
		(fp_line
			(start -0.7874 0.4064)
			(end -0.7874 -0.4064)
			(stroke
				(width 0.1524)
				(type default)
			)
			(layer "F.SilkS")
		)
		(fp_line
			(start -0.12065 -0.305054)
			(end -0.12065 -0.2794)
			(stroke
				(width 0.1)
				(type default)
			)
			(layer "F.Fab")
		)
		(fp_line
			(start -0.67945 -0.305054)
			(end -0.12065 -0.305054)
			(stroke
				(width 0.1)
				(type default)
			)
			(layer "F.Fab")
		)
		(fp_line
			(start 0.67945 -0.3048)
			(end 0.67945 0.3048)
			(stroke
				(width 0.1)
				(type default)
			)
			(layer "F.Fab")
		)
		(fp_line
			(start 0.12065 -0.3048)
			(end 0.67945 -0.3048)
			(stroke
				(width 0.1)
				(type default)
			)
			(layer "F.Fab")
		)
		(fp_line
			(start 0.12065 -0.2794)
			(end 0.12065 -0.3048)
			(stroke
				(width 0.1)
				(type default)
			)
			(layer "F.Fab")
		)
		(fp_line
			(start -0.12065 -0.2794)
			(end 0.12065 -0.2794)
			(stroke
				(width 0.1)
				(type default)
			)
			(layer "F.Fab")
		)
		(fp_line
			(start 0.120396 0.2794)
			(end -0.12065 0.2794)
			(stroke
				(width 0.1)
				(type default)
			)
			(layer "F.Fab")
		)
		(fp_line
			(start -0.12065 0.2794)
			(end -0.12065 0.3048)
			(stroke
				(width 0.1)
				(type default)
			)
			(layer "F.Fab")
		)
		(fp_line
			(start 0.67945 0.3048)
			(end 0.120396 0.3048)
			(stroke
				(width 0.1)
				(type default)
			)
			(layer "F.Fab")
		)
		(fp_line
			(start 0.120396 0.3048)
			(end 0.120396 0.2794)
			(stroke
				(width 0.1)
				(type default)
			)
			(layer "F.Fab")
		)
		(fp_line
			(start -0.12065 0.3048)
			(end -0.67945 0.3048)
			(stroke
				(width 0.1)
				(type default)
			)
			(layer "F.Fab")
		)
		(fp_line
			(start -0.67945 0.3048)
			(end -0.67945 -0.305054)
			(stroke
				(width 0.1)
				(type default)
			)
			(layer "F.Fab")
		)
		(pad "1" smd circle
			(at -0.40005 0 90)
			(size 0 0)
			(layers "F.Cu" "F.Mask" "F.Paste")
			(net "SMB_S3M_CPU0_PIROM_3V3AUX_SDA_R")
		)
		(pad "2" smd circle
			(at 0.40005 0 90)
			(size 0 0)
			(layers "F.Cu" "F.Mask" "F.Paste")
			(net "SMB_S3M_CPU0_PIROM_3V3AUX_SDA")
		)
	)
	(footprint ""
		(layer "F.Cu")
		(at 336.32648 -22.836632 -90)
		(property "Reference" "R1214"
			(at 0 0 270)
			(layer "F.SilkS")
			(hide yes)
			(effects
				(font
					(size 1.27 1.27)
				)
			)
		)
		(property "Value" ""
			(at 0 0 270)
			(layer "F.Fab")
			(effects
				(font
					(size 1.27 1.27)
				)
			)
		)
		(duplicate_pad_numbers_are_jumpers no)
		(fp_line
			(start -0.7874 0.4064)
			(end -0.7874 -0.4064)
			(stroke
				(width 0.1524)
				(type default)
			)
			(layer "F.SilkS")
		)
		(fp_line
			(start 0.7874 0.4064)
			(end -0.7874 0.4064)
			(stroke
				(width 0.1524)
				(type default)
			)
			(layer "F.SilkS")
		)
		(fp_line
			(start -0.7874 -0.4064)
			(end 0.7874 -0.4064)
			(stroke
				(width 0.1524)
				(type default)
			)
			(layer "F.SilkS")
		)
		(fp_line
			(start 0.7874 -0.4064)
			(end 0.7874 0.4064)
			(stroke
				(width 0.1524)
				(type default)
			)
			(layer "F.SilkS")
		)
		(fp_line
			(start -0.67945 0.3048)
			(end -0.67945 -0.305054)
			(stroke
				(width 0.1)
				(type default)
			)
			(layer "F.Fab")
		)
		(fp_line
			(start -0.12065 0.3048)
			(end -0.67945 0.3048)
			(stroke
				(width 0.1)
				(type default)
			)
			(layer "F.Fab")
		)
		(fp_line
			(start 0.120396 0.3048)
			(end 0.120396 0.2794)
			(stroke
				(width 0.1)
				(type default)
			)
			(layer "F.Fab")
		)
		(fp_line
			(start 0.67945 0.3048)
			(end 0.120396 0.3048)
			(stroke
				(width 0.1)
				(type default)
			)
			(layer "F.Fab")
		)
		(fp_line
			(start -0.12065 0.2794)
			(end -0.12065 0.3048)
			(stroke
				(width 0.1)
				(type default)
			)
			(layer "F.Fab")
		)
		(fp_line
			(start 0.120396 0.2794)
			(end -0.12065 0.2794)
			(stroke
				(width 0.1)
				(type default)
			)
			(layer "F.Fab")
		)
		(fp_line
			(start -0.12065 -0.2794)
			(end 0.12065 -0.2794)
			(stroke
				(width 0.1)
				(type default)
			)
			(layer "F.Fab")
		)
		(fp_line
			(start 0.12065 -0.2794)
			(end 0.12065 -0.3048)
			(stroke
				(width 0.1)
				(type default)
			)
			(layer "F.Fab")
		)
		(fp_line
			(start 0.12065 -0.3048)
			(end 0.67945 -0.3048)
			(stroke
				(width 0.1)
				(type default)
			)
			(layer "F.Fab")
		)
		(fp_line
			(start 0.67945 -0.3048)
			(end 0.67945 0.3048)
			(stroke
				(width 0.1)
				(type default)
			)
			(layer "F.Fab")
		)
		(fp_line
			(start -0.67945 -0.305054)
			(end -0.12065 -0.305054)
			(stroke
				(width 0.1)
				(type default)
			)
			(layer "F.Fab")
		)
		(fp_line
			(start -0.12065 -0.305054)
			(end -0.12065 -0.2794)
			(stroke
				(width 0.1)
				(type default)
			)
			(layer "F.Fab")
		)
		(pad "1" smd circle
			(at -0.40005 0 270)
			(size 0 0)
			(layers "F.Cu" "F.Mask" "F.Paste")
			(net "IRQ_LPC_PIRQA_N_ESPI_ALERT0_N")
		)
		(pad "2" smd circle
			(at 0.40005 0 270)
			(size 0 0)
			(layers "F.Cu" "F.Mask" "F.Paste")
			(net "IRQ_LPC_PIRQA_N_ESPI_ALERT0_R_N")
		)
	)
	(footprint ""
		(layer "F.Cu")
		(at 209.069432 -71.09079)
		(property "Reference" "R1295"
			(at 0 0 0)
			(layer "F.SilkS")
			(hide yes)
			(effects
				(font
					(size 1.27 1.27)
				)
			)
		)
		(property "Value" ""
			(at 0 0 0)
			(layer "F.Fab")
			(effects
				(font
					(size 1.27 1.27)
				)
			)
		)
		(duplicate_pad_numbers_are_jumpers no)
		(fp_line
			(start -0.7874 -0.4064)
			(end 0.7874 -0.4064)
			(stroke
				(width 0.1524)
				(type default)
			)
			(layer "F.SilkS")
		)
		(fp_line
			(start -0.7874 0.4064)
			(end -0.7874 -0.4064)
			(stroke
				(width 0.1524)
				(type default)
			)
			(layer "F.SilkS")
		)
		(fp_line
			(start 0.7874 -0.4064)
			(end 0.7874 0.4064)
			(stroke
				(width 0.1524)
				(type default)
			)
			(layer "F.SilkS")
		)
		(fp_line
			(start 0.7874 0.4064)
			(end -0.7874 0.4064)
			(stroke
				(width 0.1524)
				(type default)
			)
			(layer "F.SilkS")
		)
		(fp_line
			(start -0.67945 -0.305054)
			(end -0.12065 -0.305054)
			(stroke
				(width 0.1)
				(type default)
			)
			(layer "F.Fab")
		)
		(fp_line
			(start -0.67945 0.3048)
			(end -0.67945 -0.305054)
			(stroke
				(width 0.1)
				(type default)
			)
			(layer "F.Fab")
		)
		(fp_line
			(start -0.12065 -0.305054)
			(end -0.12065 -0.2794)
			(stroke
				(width 0.1)
				(type default)
			)
			(layer "F.Fab")
		)
		(fp_line
			(start -0.12065 -0.2794)
			(end 0.12065 -0.2794)
			(stroke
				(width 0.1)
				(type default)
			)
			(layer "F.Fab")
		)
		(fp_line
			(start -0.12065 0.2794)
			(end -0.12065 0.3048)
			(stroke
				(width 0.1)
				(type default)
			)
			(layer "F.Fab")
		)
		(fp_line
			(start -0.12065 0.3048)
			(end -0.67945 0.3048)
			(stroke
				(width 0.1)
				(type default)
			)
			(layer "F.Fab")
		)
		(fp_line
			(start 0.120396 0.2794)
			(end -0.12065 0.2794)
			(stroke
				(width 0.1)
				(type default)
			)
			(layer "F.Fab")
		)
		(fp_line
			(start 0.120396 0.3048)
			(end 0.120396 0.2794)
			(stroke
				(width 0.1)
				(type default)
			)
			(layer "F.Fab")
		)
		(fp_line
			(start 0.12065 -0.3048)
			(end 0.67945 -0.3048)
			(stroke
				(width 0.1)
				(type default)
			)
			(layer "F.Fab")
		)
		(fp_line
			(start 0.12065 -0.2794)
			(end 0.12065 -0.3048)
			(stroke
				(width 0.1)
				(type default)
			)
			(layer "F.Fab")
		)
		(fp_line
			(start 0.67945 -0.3048)
			(end 0.67945 0.3048)
			(stroke
				(width 0.1)
				(type default)
			)
			(layer "F.Fab")
		)
		(fp_line
			(start 0.67945 0.3048)
			(end 0.120396 0.3048)
			(stroke
				(width 0.1)
				(type default)
			)
			(layer "F.Fab")
		)
		(pad "1" smd circle
			(at -0.40005 0)
			(size 0 0)
			(layers "F.Cu" "F.Mask" "F.Paste")
			(net "NCSI_BMC_TXD0_R")
		)
		(pad "2" smd circle
			(at 0.40005 0)
			(size 0 0)
			(layers "F.Cu" "F.Mask" "F.Paste")
			(net "RMII_BMC_OCP_TXD_0")
		)
	)
	(footprint ""
		(layer "F.Cu")
		(at 294.045894 -414.04286)
		(property "Reference" "R4688"
			(at 0 0 0)
			(layer "F.SilkS")
			(hide yes)
			(effects
				(font
					(size 1.27 1.27)
				)
			)
		)
		(property "Value" ""
			(at 0 0 0)
			(layer "F.Fab")
			(effects
				(font
					(size 1.27 1.27)
				)
			)
		)
		(duplicate_pad_numbers_are_jumpers no)
		(fp_line
			(start -0.7874 -0.4064)
			(end 0.7874 -0.4064)
			(stroke
				(width 0.1524)
				(type default)
			)
			(layer "F.SilkS")
		)
		(fp_line
			(start -0.7874 0.4064)
			(end -0.7874 -0.4064)
			(stroke
				(width 0.1524)
				(type default)
			)
			(layer "F.SilkS")
		)
		(fp_line
			(start 0.7874 -0.4064)
			(end 0.7874 0.4064)
			(stroke
				(width 0.1524)
				(type default)
			)
			(layer "F.SilkS")
		)
		(fp_line
			(start 0.7874 0.4064)
			(end -0.7874 0.4064)
			(stroke
				(width 0.1524)
				(type default)
			)
			(layer "F.SilkS")
		)
		(fp_line
			(start -0.67945 -0.305054)
			(end -0.12065 -0.305054)
			(stroke
				(width 0.1)
				(type default)
			)
			(layer "F.Fab")
		)
		(fp_line
			(start -0.67945 0.3048)
			(end -0.67945 -0.305054)
			(stroke
				(width 0.1)
				(type default)
			)
			(layer "F.Fab")
		)
		(fp_line
			(start -0.12065 -0.305054)
			(end -0.12065 -0.2794)
			(stroke
				(width 0.1)
				(type default)
			)
			(layer "F.Fab")
		)
		(fp_line
			(start -0.12065 -0.2794)
			(end 0.12065 -0.2794)
			(stroke
				(width 0.1)
				(type default)
			)
			(layer "F.Fab")
		)
		(fp_line
			(start -0.12065 0.2794)
			(end -0.12065 0.3048)
			(stroke
				(width 0.1)
				(type default)
			)
			(layer "F.Fab")
		)
		(fp_line
			(start -0.12065 0.3048)
			(end -0.67945 0.3048)
			(stroke
				(width 0.1)
				(type default)
			)
			(layer "F.Fab")
		)
		(fp_line
			(start 0.120396 0.2794)
			(end -0.12065 0.2794)
			(stroke
				(width 0.1)
				(type default)
			)
			(layer "F.Fab")
		)
		(fp_line
			(start 0.120396 0.3048)
			(end 0.120396 0.2794)
			(stroke
				(width 0.1)
				(type default)
			)
			(layer "F.Fab")
		)
		(fp_line
			(start 0.12065 -0.3048)
			(end 0.67945 -0.3048)
			(stroke
				(width 0.1)
				(type default)
			)
			(layer "F.Fab")
		)
		(fp_line
			(start 0.12065 -0.2794)
			(end 0.12065 -0.3048)
			(stroke
				(width 0.1)
				(type default)
			)
			(layer "F.Fab")
		)
		(fp_line
			(start 0.67945 -0.3048)
			(end 0.67945 0.3048)
			(stroke
				(width 0.1)
				(type default)
			)
			(layer "F.Fab")
		)
		(fp_line
			(start 0.67945 0.3048)
			(end 0.120396 0.3048)
			(stroke
				(width 0.1)
				(type default)
			)
			(layer "F.Fab")
		)
		(pad "1" smd circle
			(at -0.40005 0)
			(size 0 0)
			(layers "F.Cu" "F.Mask" "F.Paste")
			(net "GND")
		)
		(pad "2" smd circle
			(at 0.40005 0)
			(size 0 0)
			(layers "F.Cu" "F.Mask" "F.Paste")
			(net "HSC_TYPE_ADC_A0")
		)
	)
	(footprint ""
		(layer "F.Cu")
		(at 227.048568 -233.76255 180)
		(property "Reference" "R980"
			(at 0 0 180)
			(layer "F.SilkS")
			(hide yes)
			(effects
				(font
					(size 1.27 1.27)
				)
			)
		)
		(property "Value" ""
			(at 0 0 180)
			(layer "F.Fab")
			(effects
				(font
					(size 1.27 1.27)
				)
			)
		)
		(duplicate_pad_numbers_are_jumpers no)
		(fp_line
			(start 0.7874 0.4064)
			(end -0.7874 0.4064)
			(stroke
				(width 0.1524)
				(type default)
			)
			(layer "F.SilkS")
		)
		(fp_line
			(start 0.7874 -0.4064)
			(end 0.7874 0.4064)
			(stroke
				(width 0.1524)
				(type default)
			)
			(layer "F.SilkS")
		)
		(fp_line
			(start -0.7874 0.4064)
			(end -0.7874 -0.4064)
			(stroke
				(width 0.1524)
				(type default)
			)
			(layer "F.SilkS")
		)
		(fp_line
			(start -0.7874 -0.4064)
			(end 0.7874 -0.4064)
			(stroke
				(width 0.1524)
				(type default)
			)
			(layer "F.SilkS")
		)
		(fp_line
			(start 0.67945 0.3048)
			(end 0.120396 0.3048)
			(stroke
				(width 0.1)
				(type default)
			)
			(layer "F.Fab")
		)
		(fp_line
			(start 0.67945 -0.3048)
			(end 0.67945 0.3048)
			(stroke
				(width 0.1)
				(type default)
			)
			(layer "F.Fab")
		)
		(fp_line
			(start 0.12065 -0.2794)
			(end 0.12065 -0.3048)
			(stroke
				(width 0.1)
				(type default)
			)
			(layer "F.Fab")
		)
		(fp_line
			(start 0.12065 -0.3048)
			(end 0.67945 -0.3048)
			(stroke
				(width 0.1)
				(type default)
			)
			(layer "F.Fab")
		)
		(fp_line
			(start 0.120396 0.3048)
			(end 0.120396 0.2794)
			(stroke
				(width 0.1)
				(type default)
			)
			(layer "F.Fab")
		)
		(fp_line
			(start 0.120396 0.2794)
			(end -0.12065 0.2794)
			(stroke
				(width 0.1)
				(type default)
			)
			(layer "F.Fab")
		)
		(fp_line
			(start -0.12065 0.3048)
			(end -0.67945 0.3048)
			(stroke
				(width 0.1)
				(type default)
			)
			(layer "F.Fab")
		)
		(fp_line
			(start -0.12065 0.2794)
			(end -0.12065 0.3048)
			(stroke
				(width 0.1)
				(type default)
			)
			(layer "F.Fab")
		)
		(fp_line
			(start -0.12065 -0.2794)
			(end 0.12065 -0.2794)
			(stroke
				(width 0.1)
				(type default)
			)
			(layer "F.Fab")
		)
		(fp_line
			(start -0.12065 -0.305054)
			(end -0.12065 -0.2794)
			(stroke
				(width 0.1)
				(type default)
			)
			(layer "F.Fab")
		)
		(fp_line
			(start -0.67945 0.3048)
			(end -0.67945 -0.305054)
			(stroke
				(width 0.1)
				(type default)
			)
			(layer "F.Fab")
		)
		(fp_line
			(start -0.67945 -0.305054)
			(end -0.12065 -0.305054)
			(stroke
				(width 0.1)
				(type default)
			)
			(layer "F.Fab")
		)
		(pad "1" smd circle
			(at -0.40005 0 180)
			(size 0 0)
			(layers "F.Cu" "F.Mask" "F.Paste")
			(net "P3V3_AUX")
		)
		(pad "2" smd circle
			(at 0.40005 0 180)
			(size 0 0)
			(layers "F.Cu" "F.Mask" "F.Paste")
			(net "SMB_S3M_CPU1_3V3AUX_SDA")
		)
	)
	(footprint ""
		(layer "F.Cu")
		(at 163.929314 -402.371052 -90)
		(property "Reference" "C770"
			(at 0 0 270)
			(layer "F.SilkS")
			(hide yes)
			(effects
				(font
					(size 1.27 1.27)
				)
			)
		)
		(property "Value" ""
			(at 0 0 270)
			(layer "F.Fab")
			(effects
				(font
					(size 1.27 1.27)
				)
			)
		)
		(duplicate_pad_numbers_are_jumpers no)
		(fp_line
			(start -0.299974 0.150114)
			(end -0.299974 -0.150114)
			(stroke
				(width 0.1)
				(type default)
			)
			(layer "F.Fab")
		)
		(fp_line
			(start 0.299974 0.150114)
			(end -0.299974 0.150114)
			(stroke
				(width 0.1)
				(type default)
			)
			(layer "F.Fab")
		)
		(fp_line
			(start -0.299974 -0.150114)
			(end 0.299974 -0.150114)
			(stroke
				(width 0.1)
				(type default)
			)
			(layer "F.Fab")
		)
		(fp_line
			(start 0.299974 -0.150114)
			(end 0.299974 0.150114)
			(stroke
				(width 0.1)
				(type default)
			)
			(layer "F.Fab")
		)
		(pad "1" smd rect
			(at -0.2667 0 270)
			(size 0.3048 0.381)
			(layers "F.Cu" "F.Mask" "F.Paste")
			(net "P5E_CPU1_PE2_TX_C_DN<1>")
		)
		(pad "2" smd rect
			(at 0.2667 0 270)
			(size 0.3048 0.381)
			(layers "F.Cu" "F.Mask" "F.Paste")
			(net "P5E_CPU1_PE2_TX_DN<1>")
		)
	)
)
